# S9S_MB_2U (Grand Teton) — schematic netlist excerpt (pin names and nets, part order shuffled) for the footprints in the layout excerpt that follows; sources: Cadence DE-HDL packaged netlist, KiCad conversion of 03242023_DA0F0TMBIJ0_F0T_Motherboard_J_brd_V01_OCP.brd

PU81  RS53317LR  IC  pkg QFN14_0-5_3X2XB  page 282
  PGND1  = GND
  SW1  = SW_PVNN_MAIN_CPU0_SW
  VIN  = SW_P12V_PVCCINFAON_CPU0_FLT
  CS  = PVNN_MAIN_CPU0_CS
  EN  = FM_PVNN_MAIN_CPU0_EN
  FB  = PVNN_MAIN_CPU0_FB
  AGND  = GND
  REF  = PVNN_MAIN_CPU0_REF
  PGOOD  = PWRGD_PVNN_MAIN_CPU0_R
  BST  = SW_PVNN_MAIN_CPU0_BST
  SW2  = SW_PVNN_MAIN_CPU0_SW
  MODE  = PVNN_MAIN_CPU0_MODE
  VCC  = PVNN_MAIN_CPU0_VCC
  PGND2  = GND

PC2155  Q_CAP  0.047UF 25V 10% X7R  pkg C0402  page 157 : A = P12V_OCP_SS_1 ; B = GND

(kicad_pcb
	(version 20260206)
	(generator "pcbnew")
	(generator_version "10.0")
	(general
		(thickness 1.6)
		(legacy_teardrops no)
	)
	(paper "A4")
	(title_block
		(title "03242023_DA0F0TMBIJ0_F0T_Motherboard_J_brd_V01_OCP.brd")
		(comment 1 "Grand Teton / footprints 266-267 of 6105")
	)
	(layers
		(0 "F.Cu" signal "TOP")
		(4 "In1.Cu" signal "GND")
		(6 "In2.Cu" signal "IN1")
		(8 "In3.Cu" signal "GND1")
		(10 "In4.Cu" signal "IN2")
		(12 "In5.Cu" signal "GND2")
		(14 "In6.Cu" signal "IN3")
		(16 "In7.Cu" signal "GND3")
		(18 "In8.Cu" signal "VCC")
		(20 "In9.Cu" signal "VCC1")
		(22 "In10.Cu" signal "GND4")
		(24 "In11.Cu" signal "IN4")
		(26 "In12.Cu" signal "GND5")
		(28 "In13.Cu" signal "IN5")
		(30 "In14.Cu" signal "GND6")
		(32 "In15.Cu" signal "IN6")
		(34 "In16.Cu" signal "GND7")
		(2 "B.Cu" signal "BOTTOM")
		(9 "F.Adhes" user "F.Adhesive")
		(11 "B.Adhes" user "B.Adhesive")
		(13 "F.Paste" user "Package Geometry/Pastemask Top")
		(15 "B.Paste" user "Package Geometry/Pastemask Bottom")
		(5 "F.SilkS" user "Ref Des/Silkscreen Top")
		(7 "B.SilkS" user "Ref Des/Silkscreen Bottom")
		(1 "F.Mask" user "Board Geometry/Soldermask Top")
		(3 "B.Mask" user "Board Geometry/Soldermask Bottom")
		(17 "Dwgs.User" user "User.Drawings")
		(19 "Cmts.User" user "User.Comments")
		(21 "Eco1.User" user "User.Eco1")
		(23 "Eco2.User" user "User.Eco2")
		(25 "Edge.Cuts" user "Board Geometry/Outline")
		(27 "Margin" user)
		(31 "F.CrtYd" user "Package Geometry/Place Bound Top")
		(29 "B.CrtYd" user "Package Geometry/Place Bound Bottom")
		(35 "F.Fab" user "Ref Des/Assembly Top")
		(33 "B.Fab" user "Ref Des/Assembly Bottom")
	)
	(footprint ""
		(layer "F.Cu")
		(at 432.916838 -180.97627)
		(property "Reference" "PU81"
			(at 3.54838 7.799832 0)
			(unlocked yes)
			(layer "F.SilkS")
			(effects
				(font
					(size 0.7874 0.5842)
					(thickness 0.1524)
				)
				(justify left)
			)
		)
		(property "Value" ""
			(at 0 0 0)
			(layer "F.Fab")
			(effects
				(font
					(size 1.27 1.27)
				)
			)
		)
		(duplicate_pad_numbers_are_jumpers no)
		(fp_line
			(start -1.050036 -1.549908)
			(end -0.503936 -1.549908)
			(stroke
				(width 0.1524)
				(type default)
			)
			(layer "F.SilkS")
		)
		(fp_line
			(start -1.050036 -1.253998)
			(end -1.050036 -1.549908)
			(stroke
				(width 0.1524)
				(type default)
			)
			(layer "F.SilkS")
		)
		(fp_line
			(start -1.050036 1.549908)
			(end -1.050036 1.253998)
			(stroke
				(width 0.1524)
				(type default)
			)
			(layer "F.SilkS")
		)
		(fp_line
			(start -0.503936 1.549908)
			(end -1.050036 1.549908)
			(stroke
				(width 0.1524)
				(type default)
			)
			(layer "F.SilkS")
		)
		(fp_line
			(start 0.503936 -1.549908)
			(end 1.050036 -1.549908)
			(stroke
				(width 0.1524)
				(type default)
			)
			(layer "F.SilkS")
		)
		(fp_line
			(start 1.050036 -1.549908)
			(end 1.050036 -1.253998)
			(stroke
				(width 0.1524)
				(type default)
			)
			(layer "F.SilkS")
		)
		(fp_line
			(start 1.050036 1.253998)
			(end 1.050036 1.549908)
			(stroke
				(width 0.1524)
				(type default)
			)
			(layer "F.SilkS")
		)
		(fp_line
			(start 1.050036 1.549908)
			(end 0.503936 1.549908)
			(stroke
				(width 0.1524)
				(type default)
			)
			(layer "F.SilkS")
		)
		(fp_poly
			(pts
				(xy -1.285494 -1.491742) (xy -2.093722 -1.761236) (xy -1.554988 -2.29997)
			)
			(stroke
				(width 0)
				(type default)
			)
			(fill yes)
			(layer "F.SilkS")
		)
		(fp_line
			(start -1.050036 -1.549908)
			(end 1.050036 -1.549908)
			(stroke
				(width 0.1)
				(type default)
			)
			(layer "F.Fab")
		)
		(fp_line
			(start -1.050036 1.549908)
			(end -1.050036 -1.549908)
			(stroke
				(width 0.1)
				(type default)
			)
			(layer "F.Fab")
		)
		(fp_line
			(start 1.050036 -1.549908)
			(end 1.050036 1.549908)
			(stroke
				(width 0.1)
				(type default)
			)
			(layer "F.Fab")
		)
		(fp_line
			(start 1.050036 1.549908)
			(end -1.050036 1.549908)
			(stroke
				(width 0.1)
				(type default)
			)
			(layer "F.Fab")
		)
		(fp_poly
			(pts
				(xy -2.2352 -0.618998) (xy -2.2352 -1.380998) (xy -1.4732 -0.999998)
			)
			(stroke
				(width 0)
				(type default)
			)
			(fill yes)
			(layer "F.Fab")
		)
		(pad "1" smd circle
			(at -0.94996 -0.999998 270)
			(size 0 0)
			(layers "F.Cu" "F.Mask" "F.Paste")
			(net "GND")
		)
		(pad "2" smd rect
			(at -0.849884 -0.499872 90)
			(size 0.254 0.9144)
			(layers "F.Cu" "F.Mask" "F.Paste")
			(net "SW_PVNN_MAIN_CPU0_SW")
		)
		(pad "3" smd rect
			(at -0.649986 0 90)
			(size 0.254 1.3208)
			(layers "F.Cu" "F.Mask" "F.Paste")
			(net "SW_P12V_PVCCINFAON_CPU0_FLT")
		)
		(pad "4" smd rect
			(at -0.849884 0.499872 90)
			(size 0.254 0.9144)
			(layers "F.Cu" "F.Mask" "F.Paste")
			(net "PVNN_MAIN_CPU0_CS")
		)
		(pad "5" smd circle
			(at -0.94996 0.999998 270)
			(size 0 0)
			(layers "F.Cu" "F.Mask" "F.Paste")
			(net "FM_PVNN_MAIN_CPU0_EN")
		)
		(pad "6" smd circle
			(at -0.249936 1.450086)
			(size 0 0)
			(layers "F.Cu" "F.Mask" "F.Paste")
			(net "PVNN_MAIN_CPU0_FB")
		)
		(pad "7" smd circle
			(at 0.249936 1.450086)
			(size 0 0)
			(layers "F.Cu" "F.Mask" "F.Paste")
			(net "GND")
		)
		(pad "8" smd circle
			(at 0.94996 0.999998 90)
			(size 0 0)
			(layers "F.Cu" "F.Mask" "F.Paste")
			(net "PVNN_MAIN_CPU0_REF")
		)
		(pad "9" smd rect
			(at 0.849884 0.499872 90)
			(size 0.254 0.9144)
			(layers "F.Cu" "F.Mask" "F.Paste")
			(net "PWRGD_PVNN_MAIN_CPU0_R")
		)
		(pad "10" smd rect
			(at 0.849884 0 90)
			(size 0.254 0.9144)
			(layers "F.Cu" "F.Mask" "F.Paste")
			(net "SW_PVNN_MAIN_CPU0_BST")
		)
		(pad "11" smd rect
			(at 0.849884 -0.499872 90)
			(size 0.254 0.9144)
			(layers "F.Cu" "F.Mask" "F.Paste")
			(net "SW_PVNN_MAIN_CPU0_SW")
		)
		(pad "12" smd circle
			(at 0.94996 -0.999998 90)
			(size 0 0)
			(layers "F.Cu" "F.Mask" "F.Paste")
			(net "PVNN_MAIN_CPU0_MODE")
		)
		(pad "13" smd circle
			(at 0.249936 -1.450086 180)
			(size 0 0)
			(layers "F.Cu" "F.Mask" "F.Paste")
			(net "PVNN_MAIN_CPU0_VCC")
		)
		(pad "14" smd circle
			(at -0.249936 -1.450086 180)
			(size 0 0)
			(layers "F.Cu" "F.Mask" "F.Paste")
			(net "GND")
		)
	)
	(footprint ""
		(layer "F.Cu")
		(at 441.050172 -32.173418 90)
		(property "Reference" "PC2155"
			(at 0 0 90)
			(layer "F.SilkS")
			(hide yes)
			(effects
				(font
					(size 1.27 1.27)
				)
			)
		)
		(property "Value" ""
			(at 0 0 90)
			(layer "F.Fab")
			(effects
				(font
					(size 1.27 1.27)
				)
			)
		)
		(duplicate_pad_numbers_are_jumpers no)
		(fp_line
			(start 0.7874 -0.4064)
			(end 0.7874 0.4064)
			(stroke
				(width 0.1524)
				(type default)
			)
			(layer "F.SilkS")
		)
		(fp_line
			(start -0.7874 -0.4064)
			(end 0.7874 -0.4064)
			(stroke
				(width 0.1524)
				(type default)
			)
			(layer "F.SilkS")
		)
		(fp_line
			(start 0.7874 0.4064)
			(end -0.7874 0.4064)
			(stroke
				(width 0.1524)
				(type default)
			)
			(layer "F.SilkS")
		)
		(fp_line
			(start -0.7874 0.4064)
			(end -0.7874 -0.4064)
			(stroke
				(width 0.1524)
				(type default)
			)
			(layer "F.SilkS")
		)
		(fp_line
			(start -0.12065 -0.305054)
			(end -0.12065 -0.2794)
			(stroke
				(width 0.1)
				(type default)
			)
			(layer "F.Fab")
		)
		(fp_line
			(start -0.67945 -0.305054)
			(end -0.12065 -0.305054)
			(stroke
				(width 0.1)
				(type default)
			)
			(layer "F.Fab")
		)
		(fp_line
			(start 0.67945 -0.3048)
			(end 0.67945 0.3048)
			(stroke
				(width 0.1)
				(type default)
			)
			(layer "F.Fab")
		)
		(fp_line
			(start 0.12065 -0.3048)
			(end 0.67945 -0.3048)
			(stroke
				(width 0.1)
				(type default)
			)
			(layer "F.Fab")
		)
		(fp_line
			(start 0.12065 -0.2794)
			(end 0.12065 -0.3048)
			(stroke
				(width 0.1)
				(type default)
			)
			(layer "F.Fab")
		)
		(fp_line
			(start -0.12065 -0.2794)
			(end 0.12065 -0.2794)
			(stroke
				(width 0.1)
				(type default)
			)
			(layer "F.Fab")
		)
		(fp_line
			(start 0.120396 0.2794)
			(end -0.12065 0.2794)
			(stroke
				(width 0.1)
				(type default)
			)
			(layer "F.Fab")
		)
		(fp_line
			(start -0.12065 0.2794)
			(end -0.12065 0.3048)
			(stroke
				(width 0.1)
				(type default)
			)
			(layer "F.Fab")
		)
		(fp_line
			(start 0.67945 0.3048)
			(end 0.120396 0.3048)
			(stroke
				(width 0.1)
				(type default)
			)
			(layer "F.Fab")
		)
		(fp_line
			(start 0.120396 0.3048)
			(end 0.120396 0.2794)
			(stroke
				(width 0.1)
				(type default)
			)
			(layer "F.Fab")
		)
		(fp_line
			(start -0.12065 0.3048)
			(end -0.67945 0.3048)
			(stroke
				(width 0.1)
				(type default)
			)
			(layer "F.Fab")
		)
		(fp_line
			(start -0.67945 0.3048)
			(end -0.67945 -0.305054)
			(stroke
				(width 0.1)
				(type default)
			)
			(layer "F.Fab")
		)
		(pad "1" smd circle
			(at -0.40005 0 90)
			(size 0 0)
			(layers "F.Cu" "F.Mask" "F.Paste")
			(net "P12V_OCP_SS_1")
		)
		(pad "2" smd circle
			(at 0.40005 0 90)
			(size 0 0)
			(layers "F.Cu" "F.Mask" "F.Paste")
			(net "GND")
		)
	)
)
